(kicad_pcb
	(version 20260206)
	(generator "pcbnew")
	(generator_version "10.0")
	(general
		(thickness 1.6)
		(legacy_teardrops no)
	)
	(paper "A4")
	(title_block
		(title "04192023_DAF0TMB3IC0_F0TG_MB_C_brd_V02_OCP.brd")
		(comment 1 "Grand Teton / footprint 827 of 8354 (U6017), pads 1-111 of 354")
	)
	(layers
		(0 "F.Cu" signal "TOP")
		(4 "In1.Cu" signal "GND")
		(6 "In2.Cu" signal "IN1")
		(8 "In3.Cu" signal "GND1")
		(10 "In4.Cu" signal "IN2")
		(12 "In5.Cu" signal "GND2")
		(14 "In6.Cu" signal "IN3")
		(16 "In7.Cu" signal "GND3")
		(18 "In8.Cu" signal "VCC")
		(20 "In9.Cu" signal "VCC1")
		(22 "In10.Cu" signal "GND4")
		(24 "In11.Cu" signal "IN4")
		(26 "In12.Cu" signal "GND5")
		(28 "In13.Cu" signal "IN5")
		(30 "In14.Cu" signal "GND6")
		(32 "In15.Cu" signal "IN6")
		(34 "In16.Cu" signal "GND7")
		(2 "B.Cu" signal "BOTTOM")
		(9 "F.Adhes" user "F.Adhesive")
		(11 "B.Adhes" user "B.Adhesive")
		(13 "F.Paste" user "Package Geometry/Pastemask Top")
		(15 "B.Paste" user "Package Geometry/Pastemask Bottom")
		(5 "F.SilkS" user "Ref Des/Silkscreen Top")
		(7 "B.SilkS" user "Ref Des/Silkscreen Bottom")
		(1 "F.Mask" user "Board Geometry/Soldermask Top")
		(3 "B.Mask" user "Board Geometry/Soldermask Bottom")
		(17 "Dwgs.User" user "User.Drawings")
		(19 "Cmts.User" user "User.Comments")
		(21 "Eco1.User" user "User.Eco1")
		(23 "Eco2.User" user "User.Eco2")
		(25 "Edge.Cuts" user "Board Geometry/Outline")
		(27 "Margin" user)
		(31 "F.CrtYd" user "Package Geometry/Place Bound Top")
		(29 "B.CrtYd" user "Package Geometry/Place Bound Bottom")
		(35 "F.Fab" user "Ref Des/Assembly Top")
		(33 "B.Fab" user "Ref Des/Assembly Bottom")
	)
	(footprint ""
		(layer "F.Cu")
		(at 123.567952 -387.342634)
		(property "Reference" "U6017"
			(at -6.180074 -7.979664 0)
			(unlocked yes)
			(layer "F.SilkS")
			(effects
				(font
					(size 0.7874 0.5842)
					(thickness 0.1524)
				)
				(justify left)
			)
		)
		(property "Value" ""
			(at 0 0 0)
			(layer "F.Fab")
			(effects
				(font
					(size 1.27 1.27)
				)
			)
		)
		(duplicate_pad_numbers_are_jumpers no)
		(pad "A1" smd oval
			(at 11.050016 -3.938524)
			(size 0.254 0.3302)
			(layers "F.Cu" "F.Mask" "F.Paste")
			(net "NCF_A1_CPU1_P3_GND")
		)
		(pad "A35" smd oval
			(at 11.050016 3.940048)
			(size 0.254 0.3302)
			(layers "F.Cu" "F.Mask" "F.Paste")
			(net "NCF_CPU1_P3_GND")
		)
		(pad "AA10" smd circle
			(at 7.602728 -1.431798)
			(size 0.381 0.381)
			(layers "F.Cu" "F.Mask" "F.Paste")
			(net "P5E_CPU1_P3_TX_BUF_DN<14>")
		)
		(pad "AA29" smd circle
			(at 7.602728 2.032254)
			(size 0.381 0.381)
			(layers "F.Cu" "F.Mask" "F.Paste")
			(net "P5E_CPU1_P3_RX_DN<14>")
		)
		(pad "AB1" smd oval
			(at 7.450074 -3.938524)
			(size 0.254 0.3302)
			(layers "F.Cu" "F.Mask" "F.Paste")
			(net "P5E_CPU1_P3_RX_BUF_DP<14>")
		)
		(pad "AB35" smd oval
			(at 7.450074 3.940048)
			(size 0.254 0.3302)
			(layers "F.Cu" "F.Mask" "F.Paste")
			(net "P5E_CPU1_P3_TX_C_DN<14>")
		)
		(pad "AC4" smd circle
			(at 7.202678 -2.817368)
			(size 0.381 0.381)
			(layers "F.Cu" "F.Mask" "F.Paste")
			(net "GND")
		)
		(pad "AC13" smd circle
			(at 7.202678 -0.79629)
			(size 0.3048 0.3048)
			(layers "F.Cu" "F.Mask" "F.Paste")
			(net "GND")
		)
		(pad "AC17" smd circle
			(at 7.202678 -0.296164)
			(size 0.3048 0.3048)
			(layers "F.Cu" "F.Mask" "F.Paste")
			(net "P0V9_CPU1_RT3_2A")
		)
		(pad "AC20" smd circle
			(at 7.202678 0.203708)
			(size 0.3048 0.3048)
			(layers "F.Cu" "F.Mask" "F.Paste")
			(net "P0V9_CPU1_RT3_2A")
		)
		(pad "AC22" smd circle
			(at 7.202678 0.703834)
			(size 0.3048 0.3048)
			(layers "F.Cu" "F.Mask" "F.Paste")
			(net "GND")
		)
		(pad "AC32" smd circle
			(at 7.202678 2.724912)
			(size 0.381 0.381)
			(layers "F.Cu" "F.Mask" "F.Paste")
			(net "GND")
		)
		(pad "AD2" smd circle
			(at 7.1501 -3.41884)
			(size 0.3048 0.3048)
			(layers "F.Cu" "F.Mask" "F.Paste")
			(net "GND")
		)
		(pad "AD34" smd circle
			(at 7.1501 3.420364)
			(size 0.3048 0.3048)
			(layers "F.Cu" "F.Mask" "F.Paste")
			(net "GND")
		)
		(pad "AE1" smd oval
			(at 6.849872 -3.938524)
			(size 0.254 0.3302)
			(layers "F.Cu" "F.Mask" "F.Paste")
			(net "GND")
		)
		(pad "AE35" smd oval
			(at 6.849872 3.940048)
			(size 0.254 0.3302)
			(layers "F.Cu" "F.Mask" "F.Paste")
			(net "GND")
		)
		(pad "AF7" smd circle
			(at 6.802628 -2.12471)
			(size 0.381 0.381)
			(layers "F.Cu" "F.Mask" "F.Paste")
			(net "P5E_CPU1_P3_TX_BUF_DP<13>")
		)
		(pad "AF26" smd circle
			(at 6.802628 1.339342)
			(size 0.381 0.381)
			(layers "F.Cu" "F.Mask" "F.Paste")
			(net "P5E_CPU1_P3_RX_DP<13>")
		)
		(pad "AG2" smd circle
			(at 6.549898 -3.41884)
			(size 0.3048 0.3048)
			(layers "F.Cu" "F.Mask" "F.Paste")
			(net "P5E_CPU1_P3_RX_BUF_DN<13>")
		)
		(pad "AG34" smd circle
			(at 6.549898 3.420364)
			(size 0.3048 0.3048)
			(layers "F.Cu" "F.Mask" "F.Paste")
			(net "P5E_CPU1_P3_TX_C_DN<13>")
		)
		(pad "AH10" smd circle
			(at 6.402578 -1.431798)
			(size 0.381 0.381)
			(layers "F.Cu" "F.Mask" "F.Paste")
			(net "P5E_CPU1_P3_TX_BUF_DN<13>")
		)
		(pad "AH29" smd circle
			(at 6.402578 2.032254)
			(size 0.381 0.381)
			(layers "F.Cu" "F.Mask" "F.Paste")
			(net "P5E_CPU1_P3_RX_DN<13>")
		)
		(pad "AJ1" smd oval
			(at 6.249924 -3.938524)
			(size 0.254 0.3302)
			(layers "F.Cu" "F.Mask" "F.Paste")
			(net "P5E_CPU1_P3_RX_BUF_DP<13>")
		)
		(pad "AJ35" smd oval
			(at 6.249924 3.940048)
			(size 0.254 0.3302)
			(layers "F.Cu" "F.Mask" "F.Paste")
			(net "P5E_CPU1_P3_TX_C_DP<13>")
		)
		(pad "AK4" smd circle
			(at 6.002528 -2.817368)
			(size 0.381 0.381)
			(layers "F.Cu" "F.Mask" "F.Paste")
			(net "GND")
		)
		(pad "AK13" smd circle
			(at 6.002528 -0.79629)
			(size 0.3048 0.3048)
			(layers "F.Cu" "F.Mask" "F.Paste")
			(net "GND")
		)
		(pad "AK17" smd circle
			(at 6.002528 -0.296164)
			(size 0.3048 0.3048)
			(layers "F.Cu" "F.Mask" "F.Paste")
			(net "P0V9_CPU1_RT3_2A")
		)
		(pad "AK20" smd circle
			(at 6.002528 0.203708)
			(size 0.3048 0.3048)
			(layers "F.Cu" "F.Mask" "F.Paste")
			(net "P0V9_CPU1_RT3_2A")
		)
		(pad "AK22" smd circle
			(at 6.002528 0.703834)
			(size 0.3048 0.3048)
			(layers "F.Cu" "F.Mask" "F.Paste")
			(net "GND")
		)
		(pad "AK32" smd circle
			(at 6.002528 2.724912)
			(size 0.381 0.381)
			(layers "F.Cu" "F.Mask" "F.Paste")
			(net "GND")
		)
		(pad "AL2" smd circle
			(at 5.94995 -3.41884)
			(size 0.3048 0.3048)
			(layers "F.Cu" "F.Mask" "F.Paste")
			(net "GND")
		)
		(pad "AL34" smd circle
			(at 5.94995 3.420364)
			(size 0.3048 0.3048)
			(layers "F.Cu" "F.Mask" "F.Paste")
			(net "GND")
		)
		(pad "AM1" smd oval
			(at 5.649976 -3.938524)
			(size 0.254 0.3302)
			(layers "F.Cu" "F.Mask" "F.Paste")
			(net "GND")
		)
		(pad "AM35" smd oval
			(at 5.649976 3.940048)
			(size 0.254 0.3302)
			(layers "F.Cu" "F.Mask" "F.Paste")
			(net "GND")
		)
		(pad "AN7" smd circle
			(at 5.602478 -2.12471)
			(size 0.381 0.381)
			(layers "F.Cu" "F.Mask" "F.Paste")
			(net "P5E_CPU1_P3_TX_BUF_DP<12>")
		)
		(pad "AN26" smd circle
			(at 5.602478 1.339342)
			(size 0.381 0.381)
			(layers "F.Cu" "F.Mask" "F.Paste")
			(net "P5E_CPU1_P3_RX_DP<12>")
		)
		(pad "AP2" smd circle
			(at 5.350002 -3.41884)
			(size 0.3048 0.3048)
			(layers "F.Cu" "F.Mask" "F.Paste")
			(net "P5E_CPU1_P3_RX_BUF_DN<12>")
		)
		(pad "AP34" smd circle
			(at 5.350002 3.420364)
			(size 0.3048 0.3048)
			(layers "F.Cu" "F.Mask" "F.Paste")
			(net "P5E_CPU1_P3_TX_C_DN<12>")
		)
		(pad "AR10" smd circle
			(at 5.202682 -1.431798)
			(size 0.381 0.381)
			(layers "F.Cu" "F.Mask" "F.Paste")
			(net "P5E_CPU1_P3_TX_BUF_DN<12>")
		)
		(pad "AR29" smd circle
			(at 5.202682 2.032254)
			(size 0.381 0.381)
			(layers "F.Cu" "F.Mask" "F.Paste")
			(net "P5E_CPU1_P3_RX_DN<12>")
		)
		(pad "AT1" smd oval
			(at 5.050028 -3.938524)
			(size 0.254 0.3302)
			(layers "F.Cu" "F.Mask" "F.Paste")
			(net "P5E_CPU1_P3_RX_BUF_DP<12>")
		)
		(pad "AT35" smd oval
			(at 5.050028 3.940048)
			(size 0.254 0.3302)
			(layers "F.Cu" "F.Mask" "F.Paste")
			(net "P5E_CPU1_P3_TX_C_DP<12>")
		)
		(pad "AU4" smd circle
			(at 4.802632 -2.817368)
			(size 0.381 0.381)
			(layers "F.Cu" "F.Mask" "F.Paste")
			(net "GND")
		)
		(pad "AU13" smd circle
			(at 4.802632 -0.79629)
			(size 0.3048 0.3048)
			(layers "F.Cu" "F.Mask" "F.Paste")
			(net "GND")
		)
		(pad "AU17" smd circle
			(at 4.802632 -0.296164)
			(size 0.3048 0.3048)
			(layers "F.Cu" "F.Mask" "F.Paste")
			(net "P0V9_CPU1_RT3_2A")
		)
		(pad "AU20" smd circle
			(at 4.802632 0.203708)
			(size 0.3048 0.3048)
			(layers "F.Cu" "F.Mask" "F.Paste")
			(net "P0V9_CPU1_RT3_2A")
		)
		(pad "AU22" smd circle
			(at 4.802632 0.703834)
			(size 0.3048 0.3048)
			(layers "F.Cu" "F.Mask" "F.Paste")
			(net "GND")
		)
		(pad "AU32" smd circle
			(at 4.802632 2.724912)
			(size 0.381 0.381)
			(layers "F.Cu" "F.Mask" "F.Paste")
			(net "GND")
		)
		(pad "AV2" smd circle
			(at 4.750054 -3.41884)
			(size 0.3048 0.3048)
			(layers "F.Cu" "F.Mask" "F.Paste")
			(net "GND")
		)
		(pad "AV34" smd circle
			(at 4.750054 3.420364)
			(size 0.3048 0.3048)
			(layers "F.Cu" "F.Mask" "F.Paste")
			(net "GND")
		)
		(pad "AW1" smd oval
			(at 4.45008 -3.938524)
			(size 0.254 0.3302)
			(layers "F.Cu" "F.Mask" "F.Paste")
			(net "GND")
		)
		(pad "AW35" smd oval
			(at 4.45008 3.940048)
			(size 0.254 0.3302)
			(layers "F.Cu" "F.Mask" "F.Paste")
			(net "GND")
		)
		(pad "AY7" smd circle
			(at 4.402582 -2.12471)
			(size 0.381 0.381)
			(layers "F.Cu" "F.Mask" "F.Paste")
			(net "P5E_CPU1_P3_TX_BUF_DP<11>")
		)
		(pad "AY26" smd circle
			(at 4.402582 1.339342)
			(size 0.381 0.381)
			(layers "F.Cu" "F.Mask" "F.Paste")
			(net "P5E_CPU1_P3_RX_DP<11>")
		)
		(pad "B3" smd oval
			(at 10.885932 -2.888488 90)
			(size 0.254 0.3302)
			(layers "F.Cu" "F.Mask" "F.Paste")
			(net "JTAG_TCK_RT_CPU1_P3")
		)
		(pad "B6" smd oval
			(at 10.885932 -2.288286 90)
			(size 0.254 0.3302)
			(layers "F.Cu" "F.Mask" "F.Paste")
			(net "JTAG_TDI_RT_CPU1_P3")
		)
		(pad "B9" smd oval
			(at 10.885932 -1.688338 90)
			(size 0.254 0.3302)
			(layers "F.Cu" "F.Mask" "F.Paste")
			(net "JTAG_TDO_RT_CPU1_P3")
		)
		(pad "B12" smd oval
			(at 10.885932 -1.08839 90)
			(size 0.254 0.3302)
			(layers "F.Cu" "F.Mask" "F.Paste")
			(net "JTAG_TMS_RT_CPU1_P3")
		)
		(pad "B16" smd oval
			(at 10.885932 -0.488442 90)
			(size 0.254 0.3302)
			(layers "F.Cu" "F.Mask" "F.Paste")
			(net "Net_2229")
		)
		(pad "B19" smd oval
			(at 10.885932 0.111506 90)
			(size 0.254 0.3302)
			(layers "F.Cu" "F.Mask" "F.Paste")
			(net "GND")
		)
		(pad "B23" smd oval
			(at 10.885932 0.711708 90)
			(size 0.254 0.3302)
			(layers "F.Cu" "F.Mask" "F.Paste")
			(net "RT_CPU1_P3_ADDR2")
		)
		(pad "B25" smd oval
			(at 10.885932 1.311656 90)
			(size 0.254 0.3302)
			(layers "F.Cu" "F.Mask" "F.Paste")
			(net "RT_CPU1_P3_ADDR3")
		)
		(pad "B28" smd oval
			(at 10.885932 1.911604 90)
			(size 0.254 0.3302)
			(layers "F.Cu" "F.Mask" "F.Paste")
			(net "SMB_RT_CPU1_P3_R2_SDA")
		)
		(pad "B31" smd oval
			(at 10.885932 2.511552 90)
			(size 0.254 0.3302)
			(layers "F.Cu" "F.Mask" "F.Paste")
			(net "SMB_RT_CPU1_P3_R2_SCL")
		)
		(pad "BA2" smd circle
			(at 4.150106 -3.41884)
			(size 0.3048 0.3048)
			(layers "F.Cu" "F.Mask" "F.Paste")
			(net "P5E_CPU1_P3_RX_BUF_DN<11>")
		)
		(pad "BA34" smd circle
			(at 4.150106 3.420364)
			(size 0.3048 0.3048)
			(layers "F.Cu" "F.Mask" "F.Paste")
			(net "P5E_CPU1_P3_TX_C_DN<11>")
		)
		(pad "BB10" smd circle
			(at 4.002532 -1.431798)
			(size 0.381 0.381)
			(layers "F.Cu" "F.Mask" "F.Paste")
			(net "P5E_CPU1_P3_TX_BUF_DN<11>")
		)
		(pad "BB29" smd circle
			(at 4.002532 2.032254)
			(size 0.381 0.381)
			(layers "F.Cu" "F.Mask" "F.Paste")
			(net "P5E_CPU1_P3_RX_DN<11>")
		)
		(pad "BC1" smd oval
			(at 3.849878 -3.938524)
			(size 0.254 0.3302)
			(layers "F.Cu" "F.Mask" "F.Paste")
			(net "P5E_CPU1_P3_RX_BUF_DP<11>")
		)
		(pad "BC35" smd oval
			(at 3.849878 3.940048)
			(size 0.254 0.3302)
			(layers "F.Cu" "F.Mask" "F.Paste")
			(net "P5E_CPU1_P3_TX_C_DP<11>")
		)
		(pad "BD4" smd circle
			(at 3.602482 -2.817368)
			(size 0.381 0.381)
			(layers "F.Cu" "F.Mask" "F.Paste")
			(net "GND")
		)
		(pad "BD13" smd circle
			(at 3.602482 -0.79629)
			(size 0.3048 0.3048)
			(layers "F.Cu" "F.Mask" "F.Paste")
			(net "GND")
		)
		(pad "BD17" smd circle
			(at 3.602482 -0.296164)
			(size 0.3048 0.3048)
			(layers "F.Cu" "F.Mask" "F.Paste")
			(net "P0V9_CPU1_RT3_2A_2D")
		)
		(pad "BD20" smd circle
			(at 3.602482 0.203708)
			(size 0.3048 0.3048)
			(layers "F.Cu" "F.Mask" "F.Paste")
			(net "P0V9_CPU1_RT3_2A_2D")
		)
		(pad "BD22" smd circle
			(at 3.602482 0.703834)
			(size 0.3048 0.3048)
			(layers "F.Cu" "F.Mask" "F.Paste")
			(net "GND")
		)
		(pad "BD32" smd circle
			(at 3.602482 2.724912)
			(size 0.381 0.381)
			(layers "F.Cu" "F.Mask" "F.Paste")
			(net "GND")
		)
		(pad "BE2" smd circle
			(at 3.549904 -3.41884)
			(size 0.3048 0.3048)
			(layers "F.Cu" "F.Mask" "F.Paste")
			(net "GND")
		)
		(pad "BE34" smd circle
			(at 3.549904 3.420364)
			(size 0.3048 0.3048)
			(layers "F.Cu" "F.Mask" "F.Paste")
			(net "GND")
		)
		(pad "BF1" smd oval
			(at 3.24993 -3.938524)
			(size 0.254 0.3302)
			(layers "F.Cu" "F.Mask" "F.Paste")
			(net "GND")
		)
		(pad "BF35" smd oval
			(at 3.24993 3.940048)
			(size 0.254 0.3302)
			(layers "F.Cu" "F.Mask" "F.Paste")
			(net "GND")
		)
		(pad "BG7" smd circle
			(at 3.202686 -2.12471)
			(size 0.381 0.381)
			(layers "F.Cu" "F.Mask" "F.Paste")
			(net "P5E_CPU1_P3_TX_BUF_DP<10>")
		)
		(pad "BG26" smd circle
			(at 3.202686 1.339342)
			(size 0.381 0.381)
			(layers "F.Cu" "F.Mask" "F.Paste")
			(net "P5E_CPU1_P3_RX_DP<10>")
		)
		(pad "BH2" smd circle
			(at 2.949956 -3.41884)
			(size 0.3048 0.3048)
			(layers "F.Cu" "F.Mask" "F.Paste")
			(net "P5E_CPU1_P3_RX_BUF_DN<10>")
		)
		(pad "BH34" smd circle
			(at 2.949956 3.420364)
			(size 0.3048 0.3048)
			(layers "F.Cu" "F.Mask" "F.Paste")
			(net "P5E_CPU1_P3_TX_C_DN<10>")
		)
		(pad "BJ10" smd circle
			(at 2.802636 -1.431798)
			(size 0.381 0.381)
			(layers "F.Cu" "F.Mask" "F.Paste")
			(net "P5E_CPU1_P3_TX_BUF_DN<10>")
		)
		(pad "BJ29" smd circle
			(at 2.802636 2.032254)
			(size 0.381 0.381)
			(layers "F.Cu" "F.Mask" "F.Paste")
			(net "P5E_CPU1_P3_RX_DN<10>")
		)
		(pad "BK1" smd oval
			(at 2.649982 -3.938524)
			(size 0.254 0.3302)
			(layers "F.Cu" "F.Mask" "F.Paste")
			(net "P5E_CPU1_P3_RX_BUF_DP<10>")
		)
		(pad "BK35" smd oval
			(at 2.649982 3.940048)
			(size 0.254 0.3302)
			(layers "F.Cu" "F.Mask" "F.Paste")
			(net "P5E_CPU1_P3_TX_C_DP<10>")
		)
		(pad "BL4" smd circle
			(at 2.402586 -2.817368)
			(size 0.381 0.381)
			(layers "F.Cu" "F.Mask" "F.Paste")
			(net "GND")
		)
		(pad "BL13" smd circle
			(at 2.402586 -0.79629)
			(size 0.3048 0.3048)
			(layers "F.Cu" "F.Mask" "F.Paste")
			(net "GND")
		)
		(pad "BL17" smd circle
			(at 2.402586 -0.296164)
			(size 0.3048 0.3048)
			(layers "F.Cu" "F.Mask" "F.Paste")
			(net "P0V9_CPU1_RT_2D")
		)
		(pad "BL20" smd circle
			(at 2.402586 0.203708)
			(size 0.3048 0.3048)
			(layers "F.Cu" "F.Mask" "F.Paste")
			(net "P0V9_CPU1_RT_2D")
		)
		(pad "BL22" smd circle
			(at 2.402586 0.703834)
			(size 0.3048 0.3048)
			(layers "F.Cu" "F.Mask" "F.Paste")
			(net "GND")
		)
		(pad "BL32" smd circle
			(at 2.402586 2.724912)
			(size 0.381 0.381)
			(layers "F.Cu" "F.Mask" "F.Paste")
			(net "GND")
		)
		(pad "BM2" smd circle
			(at 2.350008 -3.41884)
			(size 0.3048 0.3048)
			(layers "F.Cu" "F.Mask" "F.Paste")
			(net "GND")
		)
		(pad "BM34" smd circle
			(at 2.350008 3.420364)
			(size 0.3048 0.3048)
			(layers "F.Cu" "F.Mask" "F.Paste")
			(net "GND")
		)
		(pad "BN1" smd oval
			(at 2.050034 -3.938524)
			(size 0.254 0.3302)
			(layers "F.Cu" "F.Mask" "F.Paste")
			(net "GND")
		)
		(pad "BN35" smd oval
			(at 2.050034 3.940048)
			(size 0.254 0.3302)
			(layers "F.Cu" "F.Mask" "F.Paste")
			(net "GND")
		)
		(pad "BP7" smd circle
			(at 2.002536 -2.12471)
			(size 0.381 0.381)
			(layers "F.Cu" "F.Mask" "F.Paste")
			(net "P5E_CPU1_P3_TX_BUF_DP<9>")
		)
		(pad "BP26" smd circle
			(at 2.002536 1.339342)
			(size 0.381 0.381)
			(layers "F.Cu" "F.Mask" "F.Paste")
			(net "P5E_CPU1_P3_RX_DP<9>")
		)
		(pad "BR2" smd circle
			(at 1.75006 -3.41884)
			(size 0.3048 0.3048)
			(layers "F.Cu" "F.Mask" "F.Paste")
			(net "P5E_CPU1_P3_RX_BUF_DN<9>")
		)
		(pad "BR34" smd circle
			(at 1.75006 3.420364)
			(size 0.3048 0.3048)
			(layers "F.Cu" "F.Mask" "F.Paste")
			(net "P5E_CPU1_P3_TX_C_DN<9>")
		)
		(pad "BT10" smd circle
			(at 1.602486 -1.431798)
			(size 0.381 0.381)
			(layers "F.Cu" "F.Mask" "F.Paste")
			(net "P5E_CPU1_P3_TX_BUF_DN<9>")
		)
		(pad "BT29" smd circle
			(at 1.602486 2.032254)
			(size 0.381 0.381)
			(layers "F.Cu" "F.Mask" "F.Paste")
			(net "P5E_CPU1_P3_RX_DN<9>")
		)
		(pad "BU1" smd oval
			(at 1.450086 -3.938524)
			(size 0.254 0.3302)
			(layers "F.Cu" "F.Mask" "F.Paste")
			(net "P5E_CPU1_P3_RX_BUF_DP<9>")
		)
		(pad "BU35" smd oval
			(at 1.450086 3.940048)
			(size 0.254 0.3302)
			(layers "F.Cu" "F.Mask" "F.Paste")
			(net "P5E_CPU1_P3_TX_C_DP<9>")
		)
		(pad "BV4" smd circle
			(at 1.20269 -2.817368)
			(size 0.381 0.381)
			(layers "F.Cu" "F.Mask" "F.Paste")
			(net "GND")
		)
		(pad "BV13" smd circle
			(at 1.20269 -0.79629)
			(size 0.3048 0.3048)
			(layers "F.Cu" "F.Mask" "F.Paste")
			(net "GND")
		)
		(pad "BV17" smd circle
			(at 1.20269 -0.296164)
			(size 0.3048 0.3048)
			(layers "F.Cu" "F.Mask" "F.Paste")
			(net "P1V8_CPU1_RT3_1A_1D")
		)
		(pad "BV20" smd circle
			(at 1.20269 0.203708)
			(size 0.3048 0.3048)
			(layers "F.Cu" "F.Mask" "F.Paste")
			(net "P1V8_CPU1_RT3_1A")
		)
		(pad "BV22" smd circle
			(at 1.20269 0.703834)
			(size 0.3048 0.3048)
			(layers "F.Cu" "F.Mask" "F.Paste")
			(net "GND")
		)
	)
)
